(kicad_pcb
	(version 20260206)
	(generator "pcbnew")
	(generator_version "10.0")
	(general
		(thickness 1.6)
		(legacy_teardrops no)
	)
	(paper "A4")
	(title_block
		(title "Wiwynn_Tioga_Pass_MB.brd")
		(comment 1 "Tioga Pass / footprints 3223-3230 of 4770")
	)
	(layers
		(0 "F.Cu" signal "TOP")
		(4 "In1.Cu" signal "L2GND")
		(6 "In2.Cu" signal "L3")
		(8 "In3.Cu" signal "L4GND")
		(10 "In4.Cu" signal "L5")
		(12 "In5.Cu" signal "L6GND")
		(14 "In6.Cu" signal "L7VCC")
		(16 "In7.Cu" signal "L8VCC")
		(18 "In8.Cu" signal "L9GND")
		(20 "In9.Cu" signal "L10")
		(22 "In10.Cu" signal "L11GND")
		(24 "In11.Cu" signal "L12")
		(26 "In12.Cu" signal "L13GND")
		(2 "B.Cu" signal "BOTTOM")
		(9 "F.Adhes" user "F.Adhesive")
		(11 "B.Adhes" user "B.Adhesive")
		(13 "F.Paste" user "Package Geometry/Pastemask Top")
		(15 "B.Paste" user "Package Geometry/Pastemask Bottom")
		(5 "F.SilkS" user "Ref Des/Silkscreen Top")
		(7 "B.SilkS" user "Ref Des/Silkscreen Bottom")
		(1 "F.Mask" user "Board Geometry/Soldermask Top")
		(3 "B.Mask" user "Board Geometry/Soldermask Bottom")
		(17 "Dwgs.User" user "User.Drawings")
		(19 "Cmts.User" user "User.Comments")
		(21 "Eco1.User" user "User.Eco1")
		(23 "Eco2.User" user "User.Eco2")
		(25 "Edge.Cuts" user "Board Geometry/Outline")
		(27 "Margin" user)
		(31 "F.CrtYd" user "Package Geometry/Place Bound Top")
		(29 "B.CrtYd" user "Package Geometry/Place Bound Bottom")
		(35 "F.Fab" user "Ref Des/Assembly Top")
		(33 "B.Fab" user "Ref Des/Assembly Bottom")
	)
	(footprint ""
		(layer "B.Cu")
		(at 259.6642 -8.122412 90)
		(property "Reference" "C5U10"
			(at 0 0 90)
			(layer "B.SilkS")
			(hide yes)
			(effects
				(font
					(size 1.27 1.27)
				)
				(justify mirror)
			)
		)
		(property "Value" ""
			(at 0 0 90)
			(layer "B.Fab")
			(effects
				(font
					(size 1.27 1.27)
				)
				(justify mirror)
			)
		)
		(duplicate_pad_numbers_are_jumpers no)
		(fp_rect
			(start -0.7239 -0.2159)
			(end 0.7239 1.9939)
			(stroke
				(width 0)
				(type default)
			)
			(fill no)
			(layer "B.CrtYd")
		)
		(fp_line
			(start 0.7239 -0.2159)
			(end 0.7239 1.9939)
			(stroke
				(width 0.1)
				(type default)
			)
			(layer "B.Fab")
		)
		(fp_line
			(start -0.7239 -0.2159)
			(end 0.7239 -0.2159)
			(stroke
				(width 0.1)
				(type default)
			)
			(layer "B.Fab")
		)
		(fp_line
			(start 0.7239 1.9939)
			(end -0.7239 1.9939)
			(stroke
				(width 0.1)
				(type default)
			)
			(layer "B.Fab")
		)
		(fp_line
			(start -0.7239 1.9939)
			(end -0.7239 -0.2159)
			(stroke
				(width 0.1)
				(type default)
			)
			(layer "B.Fab")
		)
		(pad "1" smd rect
			(at 0 0 270)
			(size 1.27 1.016)
			(layers "B.Cu" "B.Mask" "B.Paste")
			(net "PVDDQ_ABC")
		)
		(pad "2" smd rect
			(at 0 1.778 270)
			(size 1.27 1.016)
			(layers "B.Cu" "B.Mask" "B.Paste")
			(net "GND")
		)
		(zone
			(layer "B.Cu")
			(hatch none 0.5)
			(connect_pads
				(clearance 0)
			)
			(min_thickness 0.25)
			(keepout
				(tracks not_allowed)
				(vias allowed)
				(pads allowed)
				(copperpour not_allowed)
				(footprints allowed)
			)
			(placement
				(enabled no)
				(sheetname "")
			)
			(fill
				(thermal_gap 0.5)
				(thermal_bridge_width 0.5)
				(island_removal_mode 0)
			)
			(polygon
				(pts
					(xy 260.1722 -7.487412) (xy 260.9342 -7.487412) (xy 260.9342 -8.757412) (xy 260.1722 -8.757412)
				)
			)
		)
	)
	(footprint ""
		(layer "B.Cu")
		(at 116.332 -76.454 90)
		(property "Reference" "R7P13"
			(at 0 0 90)
			(layer "B.SilkS")
			(hide yes)
			(effects
				(font
					(size 1.27 1.27)
				)
				(justify mirror)
			)
		)
		(property "Value" ""
			(at 0 0 90)
			(layer "B.Fab")
			(effects
				(font
					(size 1.27 1.27)
				)
				(justify mirror)
			)
		)
		(duplicate_pad_numbers_are_jumpers no)
		(fp_poly
			(pts
				(xy 0.2794 -0.1016) (xy -0.2794 -0.1016) (xy -0.2794 0.9906) (xy 0.2794 0.9906)
			)
			(stroke
				(width 0)
				(type default)
			)
			(fill no)
			(layer "B.CrtYd")
		)
		(fp_line
			(start 0.2794 -0.1016)
			(end 0.2794 0.9906)
			(stroke
				(width 0.1)
				(type default)
			)
			(layer "B.Fab")
		)
		(fp_line
			(start -0.2794 -0.1016)
			(end 0.2794 -0.1016)
			(stroke
				(width 0.1)
				(type default)
			)
			(layer "B.Fab")
		)
		(fp_line
			(start 0.2794 0.9906)
			(end -0.2794 0.9906)
			(stroke
				(width 0.1)
				(type default)
			)
			(layer "B.Fab")
		)
		(fp_line
			(start -0.2794 0.9906)
			(end -0.2794 -0.1016)
			(stroke
				(width 0.1)
				(type default)
			)
			(layer "B.Fab")
		)
		(pad "1" smd rect
			(at 0 0 270)
			(size 0.508 0.508)
			(layers "B.Cu" "B.Mask" "B.Paste")
			(net "GND")
		)
		(pad "2" smd rect
			(at 0 0.889 270)
			(size 0.508 0.508)
			(layers "B.Cu" "B.Mask" "B.Paste")
			(net "PD_CPU1_MCP01_DMON")
		)
		(zone
			(layer "B.Cu")
			(hatch none 0.5)
			(connect_pads
				(clearance 0)
			)
			(min_thickness 0.25)
			(keepout
				(tracks allowed)
				(vias not_allowed)
				(pads allowed)
				(copperpour not_allowed)
				(footprints allowed)
			)
			(placement
				(enabled no)
				(sheetname "")
			)
			(fill
				(thermal_gap 0.5)
				(thermal_bridge_width 0.5)
				(island_removal_mode 0)
			)
			(polygon
				(pts
					(xy 116.586 -76.708) (xy 116.586 -76.2) (xy 116.967 -76.2) (xy 116.967 -76.708)
				)
			)
		)
		(zone
			(layer "B.Cu")
			(hatch none 0.5)
			(connect_pads
				(clearance 0)
			)
			(min_thickness 0.25)
			(keepout
				(tracks not_allowed)
				(vias allowed)
				(pads allowed)
				(copperpour not_allowed)
				(footprints allowed)
			)
			(placement
				(enabled no)
				(sheetname "")
			)
			(fill
				(thermal_gap 0.5)
				(thermal_bridge_width 0.5)
				(island_removal_mode 0)
			)
			(polygon
				(pts
					(xy 116.967 -76.708) (xy 116.967 -76.2) (xy 116.586 -76.2) (xy 116.586 -76.708)
				)
			)
		)
	)
	(footprint ""
		(layer "B.Cu")
		(at 101.3968 -140.208 90)
		(property "Reference" "C5G106"
			(at -1.14681 0.76708 180)
			(unlocked yes)
			(layer "B.SilkS")
			(effects
				(font
					(size 0.7874 0.5842)
					(thickness 0.1524)
				)
				(justify mirror)
			)
		)
		(property "Value" ""
			(at 0 0 90)
			(layer "B.Fab")
			(effects
				(font
					(size 1.27 1.27)
				)
				(justify mirror)
			)
		)
		(duplicate_pad_numbers_are_jumpers no)
		(fp_rect
			(start -0.4953 -0.2032)
			(end 0.4953 1.6002)
			(stroke
				(width 0)
				(type default)
			)
			(fill no)
			(layer "B.CrtYd")
		)
		(fp_line
			(start 0.4953 -0.2032)
			(end -0.4953 -0.2032)
			(stroke
				(width 0.1)
				(type default)
			)
			(layer "B.Fab")
		)
		(fp_line
			(start -0.4953 -0.2032)
			(end -0.4953 1.6002)
			(stroke
				(width 0.1)
				(type default)
			)
			(layer "B.Fab")
		)
		(fp_line
			(start 0.4953 1.6002)
			(end 0.4953 -0.2032)
			(stroke
				(width 0.1)
				(type default)
			)
			(layer "B.Fab")
		)
		(fp_line
			(start -0.4953 1.6002)
			(end 0.4953 1.6002)
			(stroke
				(width 0.1)
				(type default)
			)
			(layer "B.Fab")
		)
		(pad "1" smd rect
			(at 0 0 270)
			(size 0.762 0.889)
			(layers "B.Cu" "B.Mask" "B.Paste")
			(net "PVDDQ_KLM")
		)
		(pad "2" smd rect
			(at 0 1.397 270)
			(size 0.762 0.889)
			(layers "B.Cu" "B.Mask" "B.Paste")
			(net "GND")
		)
		(zone
			(layer "B.Cu")
			(hatch none 0.5)
			(connect_pads
				(clearance 0)
			)
			(min_thickness 0.25)
			(keepout
				(tracks not_allowed)
				(vias allowed)
				(pads allowed)
				(copperpour not_allowed)
				(footprints allowed)
			)
			(placement
				(enabled no)
				(sheetname "")
			)
			(fill
				(thermal_gap 0.5)
				(thermal_bridge_width 0.5)
				(island_removal_mode 0)
			)
			(polygon
				(pts
					(xy 101.8413 -139.827) (xy 102.3493 -139.827) (xy 102.3493 -140.589) (xy 101.8413 -140.589)
				)
			)
		)
	)
	(footprint ""
		(layer "B.Cu")
		(at 268.073886 -79.60614 180)
		(property "Reference" "C5P14"
			(at 0 0 0)
			(layer "B.SilkS")
			(hide yes)
			(effects
				(font
					(size 1.27 1.27)
				)
				(justify mirror)
			)
		)
		(property "Value" ""
			(at 0 0 0)
			(layer "B.Fab")
			(effects
				(font
					(size 1.27 1.27)
				)
				(justify mirror)
			)
		)
		(duplicate_pad_numbers_are_jumpers no)
		(fp_poly
			(pts
				(xy 0.7239 -0.2159) (xy -0.7239 -0.2159) (xy -0.7239 1.9939) (xy 0.7239 1.9939)
			)
			(stroke
				(width 0)
				(type default)
			)
			(fill no)
			(layer "B.CrtYd")
		)
		(fp_line
			(start 0.7239 1.9939)
			(end -0.7239 1.9939)
			(stroke
				(width 0.1)
				(type default)
			)
			(layer "B.Fab")
		)
		(fp_line
			(start 0.7239 -0.2159)
			(end 0.7239 1.9939)
			(stroke
				(width 0.1)
				(type default)
			)
			(layer "B.Fab")
		)
		(fp_line
			(start -0.7239 1.9939)
			(end -0.7239 -0.2159)
			(stroke
				(width 0.1)
				(type default)
			)
			(layer "B.Fab")
		)
		(fp_line
			(start -0.7239 -0.2159)
			(end 0.7239 -0.2159)
			(stroke
				(width 0.1)
				(type default)
			)
			(layer "B.Fab")
		)
		(pad "1" smd rect
			(at 0 0)
			(size 1.27 1.016)
			(layers "B.Cu" "B.Mask" "B.Paste")
			(net "PVCCIN_CPU0")
		)
		(pad "2" smd rect
			(at 0 1.778)
			(size 1.27 1.016)
			(layers "B.Cu" "B.Mask" "B.Paste")
			(net "GND")
		)
		(zone
			(layer "B.Cu")
			(hatch none 0.5)
			(connect_pads
				(clearance 0)
			)
			(min_thickness 0.25)
			(keepout
				(tracks not_allowed)
				(vias allowed)
				(pads allowed)
				(copperpour not_allowed)
				(footprints allowed)
			)
			(placement
				(enabled no)
				(sheetname "")
			)
			(fill
				(thermal_gap 0.5)
				(thermal_bridge_width 0.5)
				(island_removal_mode 0)
			)
			(polygon
				(pts
					(xy 267.438886 -80.11414) (xy 268.708886 -80.11414) (xy 268.708886 -80.87614) (xy 267.438886 -80.87614)
				)
			)
		)
	)
	(footprint ""
		(layer "B.Cu")
		(at 165.1127 4.5212 180)
		(property "Reference" "C4G25"
			(at 0 0 0)
			(layer "B.SilkS")
			(hide yes)
			(effects
				(font
					(size 1.27 1.27)
				)
				(justify mirror)
			)
		)
		(property "Value" ""
			(at 0 0 0)
			(layer "B.Fab")
			(effects
				(font
					(size 1.27 1.27)
				)
				(justify mirror)
			)
		)
		(duplicate_pad_numbers_are_jumpers no)
		(fp_poly
			(pts
				(xy -0.3048 -0.1016) (xy -0.3048 0.9906) (xy 0.3048 0.9906) (xy 0.3048 -0.1016)
			)
			(stroke
				(width 0)
				(type default)
			)
			(fill no)
			(layer "B.CrtYd")
		)
		(fp_line
			(start 0.3048 0.9906)
			(end -0.3048 0.9906)
			(stroke
				(width 0.1)
				(type default)
			)
			(layer "B.Fab")
		)
		(fp_line
			(start 0.3048 -0.1016)
			(end 0.3048 0.9906)
			(stroke
				(width 0.1)
				(type default)
			)
			(layer "B.Fab")
		)
		(fp_line
			(start -0.3048 0.9906)
			(end -0.3048 -0.1016)
			(stroke
				(width 0.1)
				(type default)
			)
			(layer "B.Fab")
		)
		(fp_line
			(start -0.3048 -0.1016)
			(end 0.3048 -0.1016)
			(stroke
				(width 0.1)
				(type default)
			)
			(layer "B.Fab")
		)
		(pad "1" smd rect
			(at 0 0)
			(size 0.508 0.508)
			(layers "B.Cu" "B.Mask" "B.Paste")
			(net "PVPP_GHJ")
		)
		(pad "2" smd rect
			(at 0 0.889)
			(size 0.508 0.508)
			(layers "B.Cu" "B.Mask" "B.Paste")
			(net "GND")
		)
		(zone
			(layer "B.Cu")
			(hatch none 0.5)
			(connect_pads
				(clearance 0)
			)
			(min_thickness 0.25)
			(keepout
				(tracks not_allowed)
				(vias allowed)
				(pads allowed)
				(copperpour not_allowed)
				(footprints allowed)
			)
			(placement
				(enabled no)
				(sheetname "")
			)
			(fill
				(thermal_gap 0.5)
				(thermal_bridge_width 0.5)
				(island_removal_mode 0)
			)
			(polygon
				(pts
					(xy 164.8587 3.8862) (xy 165.3667 3.8862) (xy 165.3667 4.2672) (xy 164.8587 4.2672)
				)
			)
		)
		(zone
			(layer "B.Cu")
			(hatch none 0.5)
			(connect_pads
				(clearance 0)
			)
			(min_thickness 0.25)
			(keepout
				(tracks allowed)
				(vias not_allowed)
				(pads allowed)
				(copperpour not_allowed)
				(footprints allowed)
			)
			(placement
				(enabled no)
				(sheetname "")
			)
			(fill
				(thermal_gap 0.5)
				(thermal_bridge_width 0.5)
				(island_removal_mode 0)
			)
			(polygon
				(pts
					(xy 164.8587 4.2672) (xy 165.3667 4.2672) (xy 165.3667 3.8862) (xy 164.8587 3.8862)
				)
			)
		)
	)
	(footprint ""
		(layer "B.Cu")
		(at 265.8872 -124.6886 -90)
		(property "Reference" "R4L2"
			(at 0 0 90)
			(layer "B.SilkS")
			(hide yes)
			(effects
				(font
					(size 1.27 1.27)
				)
				(justify mirror)
			)
		)
		(property "Value" ""
			(at 0 0 90)
			(layer "B.Fab")
			(effects
				(font
					(size 1.27 1.27)
				)
				(justify mirror)
			)
		)
		(duplicate_pad_numbers_are_jumpers no)
		(fp_rect
			(start 0.2794 -0.1016)
			(end -0.2794 0.9906)
			(stroke
				(width 0)
				(type default)
			)
			(fill no)
			(layer "B.CrtYd")
		)
		(fp_line
			(start -0.2794 0.9906)
			(end -0.2794 -0.1016)
			(stroke
				(width 0.1)
				(type default)
			)
			(layer "B.Fab")
		)
		(fp_line
			(start 0.2794 0.9906)
			(end -0.2794 0.9906)
			(stroke
				(width 0.1)
				(type default)
			)
			(layer "B.Fab")
		)
		(fp_line
			(start -0.2794 -0.1016)
			(end 0.2794 -0.1016)
			(stroke
				(width 0.1)
				(type default)
			)
			(layer "B.Fab")
		)
		(fp_line
			(start 0.2794 -0.1016)
			(end 0.2794 0.9906)
			(stroke
				(width 0.1)
				(type default)
			)
			(layer "B.Fab")
		)
		(pad "1" smd rect
			(at 0 0 90)
			(size 0.508 0.508)
			(layers "B.Cu" "B.Mask" "B.Paste")
			(net "VSENSE_PVDDQ_DEF_P")
		)
		(pad "2" smd rect
			(at 0 0.889 90)
			(size 0.508 0.508)
			(layers "B.Cu" "B.Mask" "B.Paste")
			(net "VSENSE_PVDDQ_DEF_N")
		)
		(zone
			(layer "B.Cu")
			(hatch none 0.5)
			(connect_pads
				(clearance 0)
			)
			(min_thickness 0.25)
			(keepout
				(tracks allowed)
				(vias not_allowed)
				(pads allowed)
				(copperpour not_allowed)
				(footprints allowed)
			)
			(placement
				(enabled no)
				(sheetname "")
			)
			(fill
				(thermal_gap 0.5)
				(thermal_bridge_width 0.5)
				(island_removal_mode 0)
			)
			(polygon
				(pts
					(xy 265.6332 -124.4346) (xy 265.6332 -124.9426) (xy 265.2522 -124.9426) (xy 265.2522 -124.4346)
				)
			)
		)
	)
	(footprint ""
		(layer "B.Cu")
		(at 403.4282 -122.936 180)
		(property "Reference" "C2M7"
			(at 0 0 0)
			(layer "B.SilkS")
			(hide yes)
			(effects
				(font
					(size 1.27 1.27)
				)
				(justify mirror)
			)
		)
		(property "Value" ""
			(at 0 0 0)
			(layer "B.Fab")
			(effects
				(font
					(size 1.27 1.27)
				)
				(justify mirror)
			)
		)
		(duplicate_pad_numbers_are_jumpers no)
		(fp_poly
			(pts
				(xy -0.3048 -0.1016) (xy -0.3048 0.9906) (xy 0.3048 0.9906) (xy 0.3048 -0.1016)
			)
			(stroke
				(width 0)
				(type default)
			)
			(fill no)
			(layer "B.CrtYd")
		)
		(fp_line
			(start 0.3048 0.9906)
			(end -0.3048 0.9906)
			(stroke
				(width 0.1)
				(type default)
			)
			(layer "B.Fab")
		)
		(fp_line
			(start 0.3048 -0.1016)
			(end 0.3048 0.9906)
			(stroke
				(width 0.1)
				(type default)
			)
			(layer "B.Fab")
		)
		(fp_line
			(start -0.3048 0.9906)
			(end -0.3048 -0.1016)
			(stroke
				(width 0.1)
				(type default)
			)
			(layer "B.Fab")
		)
		(fp_line
			(start -0.3048 -0.1016)
			(end 0.3048 -0.1016)
			(stroke
				(width 0.1)
				(type default)
			)
			(layer "B.Fab")
		)
		(pad "1" smd rect
			(at 0 0)
			(size 0.508 0.508)
			(layers "B.Cu" "B.Mask" "B.Paste")
			(net "P1V05_PCH_STBY_WM20_PLL")
		)
		(pad "2" smd rect
			(at 0 0.889)
			(size 0.508 0.508)
			(layers "B.Cu" "B.Mask" "B.Paste")
			(net "GND")
		)
		(zone
			(layer "B.Cu")
			(hatch none 0.5)
			(connect_pads
				(clearance 0)
			)
			(min_thickness 0.25)
			(keepout
				(tracks not_allowed)
				(vias allowed)
				(pads allowed)
				(copperpour not_allowed)
				(footprints allowed)
			)
			(placement
				(enabled no)
				(sheetname "")
			)
			(fill
				(thermal_gap 0.5)
				(thermal_bridge_width 0.5)
				(island_removal_mode 0)
			)
			(polygon
				(pts
					(xy 403.1742 -123.571) (xy 403.6822 -123.571) (xy 403.6822 -123.19) (xy 403.1742 -123.19)
				)
			)
		)
		(zone
			(layer "B.Cu")
			(hatch none 0.5)
			(connect_pads
				(clearance 0)
			)
			(min_thickness 0.25)
			(keepout
				(tracks allowed)
				(vias not_allowed)
				(pads allowed)
				(copperpour not_allowed)
				(footprints allowed)
			)
			(placement
				(enabled no)
				(sheetname "")
			)
			(fill
				(thermal_gap 0.5)
				(thermal_bridge_width 0.5)
				(island_removal_mode 0)
			)
			(polygon
				(pts
					(xy 403.1742 -123.19) (xy 403.6822 -123.19) (xy 403.6822 -123.571) (xy 403.1742 -123.571)
				)
			)
		)
	)
	(footprint ""
		(layer "B.Cu")
		(at 83.856068 -3.3528 -90)
		(property "Reference" "C5G88"
			(at -1.14681 0.76708 0)
			(unlocked yes)
			(layer "B.SilkS")
			(effects
				(font
					(size 0.7874 0.5842)
					(thickness 0.1524)
				)
				(justify mirror)
			)
		)
		(property "Value" ""
			(at 0 0 90)
			(layer "B.Fab")
			(effects
				(font
					(size 1.27 1.27)
				)
				(justify mirror)
			)
		)
		(duplicate_pad_numbers_are_jumpers no)
		(fp_rect
			(start 0.4953 1.6002)
			(end -0.4953 -0.2032)
			(stroke
				(width 0)
				(type default)
			)
			(fill no)
			(layer "B.CrtYd")
		)
		(fp_line
			(start -0.4953 1.6002)
			(end 0.4953 1.6002)
			(stroke
				(width 0.1)
				(type default)
			)
			(layer "B.Fab")
		)
		(fp_line
			(start 0.4953 1.6002)
			(end 0.4953 -0.2032)
			(stroke
				(width 0.1)
				(type default)
			)
			(layer "B.Fab")
		)
		(fp_line
			(start -0.4953 -0.2032)
			(end -0.4953 1.6002)
			(stroke
				(width 0.1)
				(type default)
			)
			(layer "B.Fab")
		)
		(fp_line
			(start 0.4953 -0.2032)
			(end -0.4953 -0.2032)
			(stroke
				(width 0.1)
				(type default)
			)
			(layer "B.Fab")
		)
		(pad "1" smd rect
			(at 0 0 90)
			(size 0.762 0.889)
			(layers "B.Cu" "B.Mask" "B.Paste")
			(net "PVDDQ_GHJ")
		)
		(pad "2" smd rect
			(at 0 1.397 90)
			(size 0.762 0.889)
			(layers "B.Cu" "B.Mask" "B.Paste")
			(net "GND")
		)
		(zone
			(layer "B.Cu")
			(hatch none 0.5)
			(connect_pads
				(clearance 0)
			)
			(min_thickness 0.25)
			(keepout
				(tracks not_allowed)
				(vias allowed)
				(pads allowed)
				(copperpour not_allowed)
				(footprints allowed)
			)
			(placement
				(enabled no)
				(sheetname "")
			)
			(fill
				(thermal_gap 0.5)
				(thermal_bridge_width 0.5)
				(island_removal_mode 0)
			)
			(polygon
				(pts
					(xy 82.903568 -2.9718) (xy 83.411568 -2.9718) (xy 83.411568 -3.7338) (xy 82.903568 -3.7338)
				)
			)
		)
	)
)
